# T6G (Grand Teton) — schematic netlist excerpt (pin names and nets, part order shuffled) for the footprints in the layout excerpt that follows; sources: Cadence DE-HDL packaged netlist, KiCad conversion of 04192023_DAF0TMB3IC0_F0TG_MB_C_brd_V02_OCP.brd

DB10  TDR_3P  EMPTY  pkg TH2  page 260
  GND  = T1_GND
  IO1  = TDR_SE_50_OHM_IN3
  IO2  = TDR_SE_50_OHM_IN3

PC346  Q_CAP  2.2UF 10V 10% X6S  pkg C0402  page 216 : A = PVDDCR_SOC_P1_VCC3 ; B = GND
R2227  Q_RES  10K 1% EMPTY  pkg 0402LF  page 268 : A = A_P12V_STBY_ADR_TRIGGER ; B = GND

(kicad_pcb
	(version 20260206)
	(generator "pcbnew")
	(generator_version "10.0")
	(general
		(thickness 1.6)
		(legacy_teardrops no)
	)
	(paper "A4")
	(title_block
		(title "04192023_DAF0TMB3IC0_F0TG_MB_C_brd_V02_OCP.brd")
		(comment 1 "Grand Teton / footprints 1881-1883 of 8354")
	)
	(layers
		(0 "F.Cu" signal "TOP")
		(4 "In1.Cu" signal "GND")
		(6 "In2.Cu" signal "IN1")
		(8 "In3.Cu" signal "GND1")
		(10 "In4.Cu" signal "IN2")
		(12 "In5.Cu" signal "GND2")
		(14 "In6.Cu" signal "IN3")
		(16 "In7.Cu" signal "GND3")
		(18 "In8.Cu" signal "VCC")
		(20 "In9.Cu" signal "VCC1")
		(22 "In10.Cu" signal "GND4")
		(24 "In11.Cu" signal "IN4")
		(26 "In12.Cu" signal "GND5")
		(28 "In13.Cu" signal "IN5")
		(30 "In14.Cu" signal "GND6")
		(32 "In15.Cu" signal "IN6")
		(34 "In16.Cu" signal "GND7")
		(2 "B.Cu" signal "BOTTOM")
		(9 "F.Adhes" user "F.Adhesive")
		(11 "B.Adhes" user "B.Adhesive")
		(13 "F.Paste" user "Package Geometry/Pastemask Top")
		(15 "B.Paste" user "Package Geometry/Pastemask Bottom")
		(5 "F.SilkS" user "Ref Des/Silkscreen Top")
		(7 "B.SilkS" user "Ref Des/Silkscreen Bottom")
		(1 "F.Mask" user "Board Geometry/Soldermask Top")
		(3 "B.Mask" user "Board Geometry/Soldermask Bottom")
		(17 "Dwgs.User" user "User.Drawings")
		(19 "Cmts.User" user "User.Comments")
		(21 "Eco1.User" user "User.Eco1")
		(23 "Eco2.User" user "User.Eco2")
		(25 "Edge.Cuts" user "Board Geometry/Outline")
		(27 "Margin" user)
		(31 "F.CrtYd" user "Package Geometry/Place Bound Top")
		(29 "B.CrtYd" user "Package Geometry/Place Bound Bottom")
		(35 "F.Fab" user "Ref Des/Assembly Top")
		(33 "B.Fab" user "Ref Des/Assembly Bottom")
	)
	(footprint ""
		(layer "F.Cu")
		(at 136.10717 -153.865834 -90)
		(property "Reference" "PC346"
			(at 0 0 270)
			(layer "F.SilkS")
			(hide yes)
			(effects
				(font
					(size 1.27 1.27)
				)
			)
		)
		(property "Value" ""
			(at 0 0 270)
			(layer "F.Fab")
			(effects
				(font
					(size 1.27 1.27)
				)
			)
		)
		(duplicate_pad_numbers_are_jumpers no)
		(fp_line
			(start -0.7874 0.4064)
			(end -0.7874 -0.4064)
			(stroke
				(width 0.1524)
				(type default)
			)
			(layer "F.SilkS")
		)
		(fp_line
			(start -0.286766 0.4064)
			(end -0.7874 0.4064)
			(stroke
				(width 0.1524)
				(type default)
			)
			(layer "F.SilkS")
		)
		(fp_line
			(start 0.7874 0.4064)
			(end 0.297434 0.4064)
			(stroke
				(width 0.1524)
				(type default)
			)
			(layer "F.SilkS")
		)
		(fp_line
			(start -0.7874 -0.4064)
			(end 0.7874 -0.4064)
			(stroke
				(width 0.1524)
				(type default)
			)
			(layer "F.SilkS")
		)
		(fp_line
			(start 0.7874 -0.4064)
			(end 0.7874 0.4064)
			(stroke
				(width 0.1524)
				(type default)
			)
			(layer "F.SilkS")
		)
		(fp_line
			(start -0.67945 0.3048)
			(end -0.67945 -0.305054)
			(stroke
				(width 0.1)
				(type default)
			)
			(layer "F.Fab")
		)
		(fp_line
			(start -0.12065 0.3048)
			(end -0.67945 0.3048)
			(stroke
				(width 0.1)
				(type default)
			)
			(layer "F.Fab")
		)
		(fp_line
			(start 0.120396 0.3048)
			(end 0.120396 0.2794)
			(stroke
				(width 0.1)
				(type default)
			)
			(layer "F.Fab")
		)
		(fp_line
			(start 0.67945 0.3048)
			(end 0.120396 0.3048)
			(stroke
				(width 0.1)
				(type default)
			)
			(layer "F.Fab")
		)
		(fp_line
			(start -0.12065 0.2794)
			(end -0.12065 0.3048)
			(stroke
				(width 0.1)
				(type default)
			)
			(layer "F.Fab")
		)
		(fp_line
			(start 0.120396 0.2794)
			(end -0.12065 0.2794)
			(stroke
				(width 0.1)
				(type default)
			)
			(layer "F.Fab")
		)
		(fp_line
			(start -0.12065 -0.2794)
			(end 0.12065 -0.2794)
			(stroke
				(width 0.1)
				(type default)
			)
			(layer "F.Fab")
		)
		(fp_line
			(start 0.12065 -0.2794)
			(end 0.12065 -0.3048)
			(stroke
				(width 0.1)
				(type default)
			)
			(layer "F.Fab")
		)
		(fp_line
			(start 0.12065 -0.3048)
			(end 0.67945 -0.3048)
			(stroke
				(width 0.1)
				(type default)
			)
			(layer "F.Fab")
		)
		(fp_line
			(start 0.67945 -0.3048)
			(end 0.67945 0.3048)
			(stroke
				(width 0.1)
				(type default)
			)
			(layer "F.Fab")
		)
		(fp_line
			(start -0.67945 -0.305054)
			(end -0.12065 -0.305054)
			(stroke
				(width 0.1)
				(type default)
			)
			(layer "F.Fab")
		)
		(fp_line
			(start -0.12065 -0.305054)
			(end -0.12065 -0.2794)
			(stroke
				(width 0.1)
				(type default)
			)
			(layer "F.Fab")
		)
		(pad "1" smd circle
			(at -0.40005 0 270)
			(size 0 0)
			(layers "F.Cu" "F.Mask" "F.Paste")
			(net "PVDDCR_SOC_P1_VCC3")
		)
		(pad "2" smd circle
			(at 0.40005 0 270)
			(size 0 0)
			(layers "F.Cu" "F.Mask" "F.Paste")
			(net "GND")
		)
	)
	(footprint ""
		(layer "F.Cu")
		(at 479.38436 -107.699302 180)
		(property "Reference" "DB10"
			(at -1.716024 2.8194 0)
			(unlocked yes)
			(layer "F.SilkS")
			(effects
				(font
					(size 0.7874 0.5842)
					(thickness 0.1524)
				)
				(justify left)
			)
		)
		(property "Value" ""
			(at 0 0 180)
			(layer "F.Fab")
			(effects
				(font
					(size 1.27 1.27)
				)
			)
		)
		(duplicate_pad_numbers_are_jumpers no)
		(fp_line
			(start 3.330702 -4.771136)
			(end 0 4.011168)
			(stroke
				(width 0.1524)
				(type default)
			)
			(layer "F.SilkS")
		)
		(fp_line
			(start 0 4.011168)
			(end -3.330702 -4.771136)
			(stroke
				(width 0.1524)
				(type default)
			)
			(layer "F.SilkS")
		)
		(fp_line
			(start -3.330702 -4.771136)
			(end 3.330702 -4.771136)
			(stroke
				(width 0.1524)
				(type default)
			)
			(layer "F.SilkS")
		)
		(fp_line
			(start 3.330702 -4.771136)
			(end 0 4.011168)
			(stroke
				(width 0.1)
				(type default)
			)
			(layer "F.Fab")
		)
		(fp_line
			(start 0 4.011168)
			(end -3.330702 -4.771136)
			(stroke
				(width 0.1)
				(type default)
			)
			(layer "F.Fab")
		)
		(fp_line
			(start -3.330702 -4.771136)
			(end 3.330702 -4.771136)
			(stroke
				(width 0.1)
				(type default)
			)
			(layer "F.Fab")
		)
		(pad "1" thru_hole circle
			(at 0 0 180)
			(size 2.159 2.159)
			(drill 1.7018)
			(layers "*.Cu" "*.Mask")
			(remove_unused_layers no)
			(net "T1_GND")
			(clearance 0.0254)
			(thermal_gap 0.0254)
		)
		(pad "2" thru_hole circle
			(at -1.27 -3.348736 180)
			(size 2.159 2.159)
			(drill 1.7018)
			(layers "*.Cu" "*.Mask")
			(remove_unused_layers no)
			(net "TDR_SE_50_OHM_IN3")
			(clearance 0.0254)
			(thermal_gap 0.0254)
		)
		(pad "3" thru_hole circle
			(at 1.27 -3.348736 180)
			(size 2.159 2.159)
			(drill 1.7018)
			(layers "*.Cu" "*.Mask")
			(remove_unused_layers no)
			(net "TDR_SE_50_OHM_IN3")
			(clearance 0.0254)
			(thermal_gap 0.0254)
		)
	)
	(footprint ""
		(layer "F.Cu")
		(at 160.380934 -120.40108)
		(property "Reference" "R2227"
			(at 0 0 0)
			(layer "F.SilkS")
			(hide yes)
			(effects
				(font
					(size 1.27 1.27)
				)
			)
		)
		(property "Value" ""
			(at 0 0 0)
			(layer "F.Fab")
			(effects
				(font
					(size 1.27 1.27)
				)
			)
		)
		(duplicate_pad_numbers_are_jumpers no)
		(fp_line
			(start -0.7874 -0.4064)
			(end 0.7874 -0.4064)
			(stroke
				(width 0.1524)
				(type default)
			)
			(layer "F.SilkS")
		)
		(fp_line
			(start -0.7874 0.4064)
			(end -0.7874 -0.4064)
			(stroke
				(width 0.1524)
				(type default)
			)
			(layer "F.SilkS")
		)
		(fp_line
			(start 0.7874 -0.4064)
			(end 0.7874 0.4064)
			(stroke
				(width 0.1524)
				(type default)
			)
			(layer "F.SilkS")
		)
		(fp_line
			(start 0.7874 0.4064)
			(end -0.7874 0.4064)
			(stroke
				(width 0.1524)
				(type default)
			)
			(layer "F.SilkS")
		)
		(fp_line
			(start -0.67945 -0.305054)
			(end -0.12065 -0.305054)
			(stroke
				(width 0.1)
				(type default)
			)
			(layer "F.Fab")
		)
		(fp_line
			(start -0.67945 0.3048)
			(end -0.67945 -0.305054)
			(stroke
				(width 0.1)
				(type default)
			)
			(layer "F.Fab")
		)
		(fp_line
			(start -0.12065 -0.305054)
			(end -0.12065 -0.2794)
			(stroke
				(width 0.1)
				(type default)
			)
			(layer "F.Fab")
		)
		(fp_line
			(start -0.12065 -0.2794)
			(end 0.12065 -0.2794)
			(stroke
				(width 0.1)
				(type default)
			)
			(layer "F.Fab")
		)
		(fp_line
			(start -0.12065 0.2794)
			(end -0.12065 0.3048)
			(stroke
				(width 0.1)
				(type default)
			)
			(layer "F.Fab")
		)
		(fp_line
			(start -0.12065 0.3048)
			(end -0.67945 0.3048)
			(stroke
				(width 0.1)
				(type default)
			)
			(layer "F.Fab")
		)
		(fp_line
			(start 0.120396 0.2794)
			(end -0.12065 0.2794)
			(stroke
				(width 0.1)
				(type default)
			)
			(layer "F.Fab")
		)
		(fp_line
			(start 0.120396 0.3048)
			(end 0.120396 0.2794)
			(stroke
				(width 0.1)
				(type default)
			)
			(layer "F.Fab")
		)
		(fp_line
			(start 0.12065 -0.3048)
			(end 0.67945 -0.3048)
			(stroke
				(width 0.1)
				(type default)
			)
			(layer "F.Fab")
		)
		(fp_line
			(start 0.12065 -0.2794)
			(end 0.12065 -0.3048)
			(stroke
				(width 0.1)
				(type default)
			)
			(layer "F.Fab")
		)
		(fp_line
			(start 0.67945 -0.3048)
			(end 0.67945 0.3048)
			(stroke
				(width 0.1)
				(type default)
			)
			(layer "F.Fab")
		)
		(fp_line
			(start 0.67945 0.3048)
			(end 0.120396 0.3048)
			(stroke
				(width 0.1)
				(type default)
			)
			(layer "F.Fab")
		)
		(pad "1" smd circle
			(at -0.40005 0)
			(size 0 0)
			(layers "F.Cu" "F.Mask" "F.Paste")
			(net "A_P12V_STBY_ADR_TRIGGER")
		)
		(pad "2" smd circle
			(at 0.40005 0)
			(size 0 0)
			(layers "F.Cu" "F.Mask" "F.Paste")
			(net "GND")
		)
	)
)
